#ISCELL
  mstr_symbols cad_note *
  *
#ISCELL
  mstr_symbols intel_corp_bpage *
  *
#CELL
  mstr_discrete cap *
  page105_i1
#ISCELL
  mstr_standard tap *
  page105_i10
#ISCELL
  mstr_standard tap *
  page105_i11
#CELL
  mstr_discrete cap *
  page105_i12
#CELL
  mstr_discrete cap *
  page105_i13
#ISCELL
  mstr_standard tap *
  page105_i14
#ISCELL
  mstr_standard tap *
  page105_i15
#ISCELL
  mstr_standard tap *
  page105_i151
#ISCELL
  mstr_standard tap *
  page105_i152
#CELL
  mstr_discrete cap *
  page105_i153
#ISCELL
  mstr_standard tap *
  page105_i154
#ISCELL
  mstr_standard tap *
  page105_i155
#ISCELL
  mstr_standard tap *
  page105_i156
#ISCELL
  mstr_standard tap *
  page105_i157
#ISCELL
  mstr_standard tap *
  page105_i158
#ISCELL
  mstr_standard tap *
  page105_i159
#ISCELL
  mstr_standard tap *
  page105_i16
#CELL
  mstr_discrete cap *
  page105_i160
#ISCELL
  mstr_standard tap *
  page105_i161
#ISCELL
  mstr_standard tap *
  page105_i162
#CELL
  mstr_discrete cap *
  page105_i163
#ISCELL
  mstr_standard tap *
  page105_i164
#ISCELL
  mstr_standard tap *
  page105_i165
#CELL
  mstr_discrete cap *
  page105_i166
#ISCELL
  mstr_standard tap *
  page105_i167
#ISCELL
  mstr_standard tap *
  page105_i168
#CELL
  mstr_discrete cap *
  page105_i169
#ISCELL
  mstr_standard tap *
  page105_i17
#ISCELL
  mstr_standard tap *
  page105_i170
#ISCELL
  mstr_standard offpage *
  page105_i171
#ISCELL
  mstr_standard tap *
  page105_i172
#CELL
  mstr_discrete cap *
  page105_i173
#ISCELL
  mstr_standard tap *
  page105_i174
#CELL
  mstr_discrete cap *
  page105_i175
#ISCELL
  mstr_standard tap *
  page105_i176
#ISCELL
  mstr_standard tap *
  page105_i177
#ISCELL
  mstr_standard tap *
  page105_i178
#ISCELL
  mstr_standard tap *
  page105_i179
#ISCELL
  mstr_standard tap *
  page105_i18
#CELL
  mstr_discrete cap *
  page105_i180
#CELL
  mstr_discrete cap *
  page105_i181
#ISCELL
  mstr_standard tap *
  page105_i182
#ISCELL
  mstr_standard tap *
  page105_i183
#ISCELL
  mstr_standard tap *
  page105_i184
#CELL
  mstr_discrete cap *
  page105_i185
#ISCELL
  mstr_standard tap *
  page105_i186
#CELL
  mstr_discrete cap *
  page105_i187
#ISCELL
  mstr_standard tap *
  page105_i188
#CELL
  mstr_discrete cap *
  page105_i189
#ISCELL
  mstr_standard tap *
  page105_i19
#ISCELL
  mstr_standard tap *
  page105_i190
#ISCELL
  mstr_standard tap *
  page105_i191
#ISCELL
  mstr_standard tap *
  page105_i192
#CELL
  mstr_discrete cap *
  page105_i193
#ISCELL
  mstr_standard tap *
  page105_i194
#ISCELL
  mstr_standard tap *
  page105_i195
#CELL
  mstr_discrete cap *
  page105_i196
#ISCELL
  mstr_standard tap *
  page105_i197
#CELL
  mstr_discrete cap *
  page105_i198
#ISCELL
  mstr_standard offpage *
  page105_i199
#CELL
  mstr_discrete cap *
  page105_i20
#ISCELL
  mstr_standard tap *
  page105_i200
#CELL
  mstr_discrete cap *
  page105_i201
#ISCELL
  mstr_standard tap *
  page105_i202
#ISCELL
  mstr_standard offpage *
  page105_i203
#ISCELL
  mstr_standard offpage *
  page105_i204
#CELL
  mstr_discrete cap *
  page105_i205
#CELL
  mstr_discrete cap *
  page105_i206
#ISCELL
  mstr_standard offpage *
  page105_i207
#ISCELL
  mstr_standard offpage *
  page105_i208
#ISCELL
  mstr_standard tap *
  page105_i209
#CELL
  mstr_discrete cap *
  page105_i21
#ISCELL
  mstr_standard tap *
  page105_i210
#ISCELL
  mstr_standard tap *
  page105_i211
#CELL
  mstr_discrete cap *
  page105_i212
#ISCELL
  mstr_standard tap *
  page105_i213
#ISCELL
  mstr_standard tap *
  page105_i214
#ISCELL
  mstr_standard tap *
  page105_i215
#ISCELL
  mstr_standard tap *
  page105_i216
#CELL
  mstr_discrete cap *
  page105_i217
#CELL
  mstr_discrete cap *
  page105_i218
#ISCELL
  mstr_standard tap *
  page105_i219
#CELL
  mstr_discrete cap *
  page105_i22
#ISCELL
  mstr_standard tap *
  page105_i220
#ISCELL
  mstr_standard tap *
  page105_i221
#ISCELL
  mstr_standard tap *
  page105_i222
#CELL
  mstr_discrete cap *
  page105_i223
#ISCELL
  mstr_standard tap *
  page105_i224
#CELL
  mstr_discrete cap *
  page105_i225
#ISCELL
  mstr_standard tap *
  page105_i226
#ISCELL
  mstr_standard tap *
  page105_i227
#ISCELL
  mstr_standard tap *
  page105_i228
#CELL
  mstr_discrete cap *
  page105_i229
#ISCELL
  mstr_standard tap *
  page105_i23
#ISCELL
  mstr_standard tap *
  page105_i230
#ISCELL
  mstr_standard tap *
  page105_i231
#CELL
  mstr_discrete cap *
  page105_i232
#ISCELL
  mstr_standard tap *
  page105_i233
#CELL
  mstr_discrete cap *
  page105_i234
#ISCELL
  mstr_standard tap *
  page105_i235
#ISCELL
  mstr_standard tap *
  page105_i236
#ISCELL
  mstr_standard offpage *
  page105_i237
#ISCELL
  mstr_standard tap *
  page105_i238
#CELL
  mstr_discrete cap *
  page105_i239
#ISCELL
  mstr_standard tap *
  page105_i24
#ISCELL
  mstr_standard tap *
  page105_i240
#ISCELL
  mstr_standard tap *
  page105_i241
#ISCELL
  mstr_standard tap *
  page105_i242
#ISCELL
  mstr_standard tap *
  page105_i243
#CELL
  mstr_discrete cap *
  page105_i244
#ISCELL
  mstr_standard tap *
  page105_i245
#CELL
  mstr_discrete cap *
  page105_i246
#CELL
  mstr_discrete cap *
  page105_i247
#ISCELL
  mstr_standard tap *
  page105_i248
#ISCELL
  mstr_standard offpage *
  page105_i249
#ISCELL
  mstr_standard tap *
  page105_i25
#ISCELL
  mstr_standard tap *
  page105_i250
#ISCELL
  mstr_standard tap *
  page105_i251
#ISCELL
  mstr_standard tap *
  page105_i252
#CELL
  mstr_discrete cap *
  page105_i253
#ISCELL
  mstr_standard tap *
  page105_i254
#CELL
  mstr_discrete cap *
  page105_i255
#ISCELL
  mstr_standard tap *
  page105_i256
#CELL
  mstr_discrete cap *
  page105_i257
#CELL
  mstr_discrete cap *
  page105_i258
#ISCELL
  mstr_standard tap *
  page105_i26
#CELL
  mstr_discrete cap *
  page105_i27
#CELL
  mstr_discrete cap *
  page105_i28
#ISCELL
  mstr_standard tap *
  page105_i29
#ISCELL
  mstr_standard offpage *
  page105_i3
#ISCELL
  mstr_standard tap *
  page105_i30
#CELL
  mstr_discrete cap *
  page105_i31
#CELL
  mstr_discrete cap *
  page105_i32
#ISCELL
  mstr_standard tap *
  page105_i33
#ISCELL
  mstr_standard tap *
  page105_i35
#ISCELL
  mstr_standard tap *
  page105_i36
#CELL
  mstr_discrete cap *
  page105_i37
#ISCELL
  mstr_standard tap *
  page105_i38
#ISCELL
  mstr_standard tap *
  page105_i39
#ISCELL
  mstr_standard tap *
  page105_i4
#ISCELL
  mstr_standard tap *
  page105_i40
#ISCELL
  mstr_standard tap *
  page105_i41
#ISCELL
  mstr_standard tap *
  page105_i42
#ISCELL
  mstr_standard tap *
  page105_i43
#CELL
  mstr_discrete cap *
  page105_i44
#CELL
  mstr_discrete cap *
  page105_i45
#ISCELL
  mstr_standard tap *
  page105_i47
#ISCELL
  mstr_standard tap *
  page105_i48
#ISCELL
  mstr_standard tap *
  page105_i49
#ISCELL
  mstr_standard tap *
  page105_i5
#ISCELL
  mstr_standard tap *
  page105_i50
#CELL
  mstr_discrete cap *
  page105_i51
#CELL
  mstr_discrete cap *
  page105_i52
#ISCELL
  mstr_standard tap *
  page105_i53
#ISCELL
  mstr_standard tap *
  page105_i54
#CELL
  mstr_discrete cap *
  page105_i55
#CELL
  mstr_discrete cap *
  page105_i56
#ISCELL
  mstr_standard tap *
  page105_i57
#CELL
  mstr_discrete cap *
  page105_i58
#ISCELL
  mstr_standard tap *
  page105_i59
#CELL
  mstr_discrete cap *
  page105_i6
#ISCELL
  mstr_standard tap *
  page105_i60
#CELL
  mstr_discrete cap *
  page105_i61
#CELL
  mstr_discrete cap *
  page105_i62
#ISCELL
  mstr_standard tap *
  page105_i63
#ISCELL
  mstr_standard tap *
  page105_i64
#ISCELL
  mstr_standard tap *
  page105_i65
#ISCELL
  mstr_standard tap *
  page105_i66
#ISCELL
  mstr_standard tap *
  page105_i67
#ISCELL
  mstr_standard tap *
  page105_i68
#CELL
  mstr_discrete cap *
  page105_i69
#CELL
  mstr_discrete cap *
  page105_i7
#CELL
  mstr_discrete cap *
  page105_i70
#CELL
  mstr_discrete cap *
  page105_i71
#ISCELL
  mstr_standard tap *
  page105_i72
#ISCELL
  mstr_standard tap *
  page105_i73
#ISCELL
  mstr_standard tap *
  page105_i74
#CELL
  mstr_discrete cap *
  page105_i75
#CELL
  mstr_discrete cap *
  page105_i76
#ISCELL
  mstr_standard offpage *
  page105_i77
#ISCELL
  mstr_standard tap *
  page105_i78
#ISCELL
  mstr_standard tap *
  page105_i79
#CELL
  mstr_discrete cap *
  page105_i8
#ISCELL
  mstr_standard tap *
  page105_i80
#ISCELL
  mstr_standard tap *
  page105_i81
#ISCELL
  mstr_standard tap *
  page105_i82
#ISCELL
  mstr_standard tap *
  page105_i83
#ISCELL
  mstr_standard tap *
  page105_i84
#ISCELL
  mstr_standard tap *
  page105_i85
#ISCELL
  mstr_standard tap *
  page105_i86
#ISCELL
  mstr_standard tap *
  page105_i87
#ISCELL
  mstr_standard tap *
  page105_i88
#ISCELL
  mstr_standard tap *
  page105_i89
#ISCELL
  mstr_standard tap *
  page105_i9
#ISCELL
  mstr_standard tap *
  page105_i90
#ISCELL
  mstr_standard tap *
  page105_i91
#ISCELL
  mstr_standard tap *
  page105_i92
#CELL
  mstr_discrete cap *
  page105_i93
#ISCELL
  mstr_standard tap *
  page105_i94
#ISCELL
  mstr_standard offpage *
  page105_i95
#CELL
  mstr_discrete cap *
  page105_i96
#ISCELL
  mstr_standard tap *
  page105_i97
#ISCELL
  mstr_standard tap *
  page105_i98
#ISCELL
  mstr_standard offpage *
  page105_i99
